(kicad_pcb
	(version 20260206)
	(generator "pcbnew")
	(generator_version "10.0")
	(general
		(thickness 1.6)
		(legacy_teardrops no)
	)
	(paper "A4")
	(title_block
		(title "Bryce Canyon_IOM_IOC_16318-2_OCP.brd")
		(comment 1 "Bryce Canyon / footprints 1100-1105 of 1605")
	)
	(layers
		(0 "F.Cu" signal "TOP")
		(4 "In1.Cu" signal "L2GND")
		(6 "In2.Cu" signal "L3")
		(8 "In3.Cu" signal "L4VCC")
		(10 "In4.Cu" signal "L5VCC")
		(12 "In5.Cu" signal "L6")
		(14 "In6.Cu" signal "L7GND")
		(2 "B.Cu" signal "BOTTOM")
		(9 "F.Adhes" user "F.Adhesive")
		(11 "B.Adhes" user "B.Adhesive")
		(13 "F.Paste" user "Package Geometry/Pastemask Top")
		(15 "B.Paste" user "Package Geometry/Pastemask Bottom")
		(5 "F.SilkS" user "Ref Des/Silkscreen Top")
		(7 "B.SilkS" user "Ref Des/Silkscreen Bottom")
		(1 "F.Mask" user "Board Geometry/Soldermask Top")
		(3 "B.Mask" user "Board Geometry/Soldermask Bottom")
		(17 "Dwgs.User" user "User.Drawings")
		(19 "Cmts.User" user "User.Comments")
		(21 "Eco1.User" user "User.Eco1")
		(23 "Eco2.User" user "User.Eco2")
		(25 "Edge.Cuts" user "Board Geometry/Outline")
		(27 "Margin" user)
		(31 "F.CrtYd" user "Package Geometry/Place Bound Top")
		(29 "B.CrtYd" user "Package Geometry/Place Bound Bottom")
		(35 "F.Fab" user "Ref Des/Assembly Top")
		(33 "B.Fab" user "Ref Des/Assembly Bottom")
	)
	(footprint ""
		(layer "B.Cu")
		(at 84.582 -130.048 90)
		(property "Reference" "R718"
			(at 0 0 90)
			(layer "B.SilkS")
			(hide yes)
			(effects
				(font
					(size 1.27 1.27)
				)
				(justify mirror)
			)
		)
		(property "Value" "0R2J-2-GP"
			(at -0.064008 -3.993896 90)
			(unlocked yes)
			(layer "B.Fab")
			(hide yes)
			(effects
				(font
					(size 1.016 1.016)
					(thickness 0.1524)
				)
				(justify mirror)
			)
		)
		(property "Device Type" "R402H16"
			(at -0.064008 -5.517896 90)
			(unlocked yes)
			(layer "B.Fab")
			(hide yes)
			(effects
				(font
					(size 1.016 1.016)
					(thickness 0.1524)
				)
				(justify mirror)
			)
		)
		(duplicate_pad_numbers_are_jumpers no)
		(fp_line
			(start 0.508 -0.9398)
			(end 0.508 0.9398)
			(stroke
				(width 0.1524)
				(type default)
			)
			(layer "B.SilkS")
		)
		(fp_line
			(start -0.508 -0.9398)
			(end 0.508 -0.9398)
			(stroke
				(width 0.1524)
				(type default)
			)
			(layer "B.SilkS")
		)
		(fp_rect
			(start 0.508 0.9398)
			(end -0.508 -0.9398)
			(stroke
				(width 0)
				(type default)
			)
			(fill no)
			(layer "B.CrtYd")
		)
		(fp_rect
			(start 0.508 0.9398)
			(end -0.508 -0.9398)
			(stroke
				(width 0)
				(type default)
			)
			(fill no)
			(layer "B.Fab")
		)
		(pad "1" smd custom
			(at 0 -0.4445 270)
			(size 0.1397 0.1397)
			(layers "B.Cu" "B.Mask" "B.Paste")
			(net "BMC_TO_EXP_RESET_OUT_R")
			(options
				(clearance outline)
				(anchor circle)
			)
			(primitives
				(gr_poly
					(pts
						(arc
							(start -0.1778 0.2794)
							(mid -0.249642 0.249642)
							(end -0.2794 0.1778)
						)
						(arc
							(start -0.2794 -0.1778)
							(mid -0.249642 -0.249642)
							(end -0.1778 -0.2794)
						)
						(arc
							(start 0.1778 -0.2794)
							(mid 0.249642 -0.249642)
							(end 0.2794 -0.1778)
						)
						(arc
							(start 0.2794 0.1778)
							(mid 0.249642 0.249642)
							(end 0.1778 0.2794)
						)
					)
					(width 0)
					(fill yes)
				)
			)
		)
		(pad "2" smd custom
			(at 0 0.4445 270)
			(size 0.1397 0.1397)
			(layers "B.Cu" "B.Mask" "B.Paste")
			(net "BMC_TO_EXP_RESET_OUT")
			(options
				(clearance outline)
				(anchor circle)
			)
			(primitives
				(gr_poly
					(pts
						(arc
							(start -0.1778 0.2794)
							(mid -0.249642 0.249642)
							(end -0.2794 0.1778)
						)
						(arc
							(start -0.2794 -0.1778)
							(mid -0.249642 -0.249642)
							(end -0.1778 -0.2794)
						)
						(arc
							(start 0.1778 -0.2794)
							(mid 0.249642 -0.249642)
							(end 0.2794 -0.1778)
						)
						(arc
							(start 0.2794 0.1778)
							(mid 0.249642 0.249642)
							(end 0.1778 0.2794)
						)
					)
					(width 0)
					(fill yes)
				)
			)
		)
	)
	(footprint ""
		(layer "B.Cu")
		(at 56.690768 -144.018)
		(property "Reference" "TP79"
			(at 0 0 0)
			(layer "B.SilkS")
			(hide yes)
			(effects
				(font
					(size 1.27 1.27)
				)
				(justify mirror)
			)
		)
		(property "Value" "TPAD28-2-GP"
			(at 0.0127 -1.6637 0)
			(unlocked yes)
			(layer "B.Fab")
			(hide yes)
			(effects
				(font
					(size 1.016 1.016)
					(thickness 0.1524)
				)
				(justify mirror)
			)
		)
		(property "Device Type" "TPAD28"
			(at 0.0127 -3.1877 0)
			(unlocked yes)
			(layer "B.Fab")
			(hide yes)
			(effects
				(font
					(size 1.016 1.016)
					(thickness 0.1524)
				)
				(justify mirror)
			)
		)
		(duplicate_pad_numbers_are_jumpers no)
		(fp_poly
			(pts
				(arc
					(start 0.3556 0)
					(mid -0.3556 0)
					(end 0.3556 0)
				)
			)
			(stroke
				(width 0)
				(type default)
			)
			(fill no)
			(layer "B.CrtYd")
		)
		(fp_poly
			(pts
				(arc
					(start 0.6096 0)
					(mid -0.6096 0)
					(end 0.6096 0)
				)
			)
			(stroke
				(width 0)
				(type default)
			)
			(fill no)
			(layer "B.Fab")
		)
		(pad "1" smd circle
			(at 0 0 180)
			(size 0.7112 0.7112)
			(layers "B.Cu" "B.Mask" "B.Paste")
			(net "JTAG_BMC_TDI")
		)
	)
	(footprint ""
		(layer "B.Cu")
		(at 201.092308 -52.969668 -90)
		(property "Reference" "C337"
			(at 0 0 90)
			(layer "B.SilkS")
			(hide yes)
			(effects
				(font
					(size 1.27 1.27)
				)
				(justify mirror)
			)
		)
		(property "Value" "SC1U6D3V1MX-GP"
			(at -1.9177 2.0193 270)
			(unlocked yes)
			(layer "B.Fab")
			(hide yes)
			(effects
				(font
					(size 1.016 1.016)
					(thickness 0.1524)
				)
				(justify mirror)
			)
		)
		(property "Device Type" "C0201H14"
			(at -1.9177 0.4953 270)
			(unlocked yes)
			(layer "B.Fab")
			(hide yes)
			(effects
				(font
					(size 1.016 1.016)
					(thickness 0.1524)
				)
				(justify mirror)
			)
		)
		(duplicate_pad_numbers_are_jumpers no)
		(fp_rect
			(start 0.1524 0.3048)
			(end -0.1524 -0.3048)
			(stroke
				(width 0)
				(type default)
			)
			(fill no)
			(layer "B.CrtYd")
		)
		(fp_poly
			(pts
				(xy 0.2794 0.6477) (xy 0.2794 -0.6477) (xy -0.2794 -0.6477) (xy -0.2794 -0.1905) (xy -0.1524 -0.1905)
				(xy -0.1524 -0.3048) (xy 0.1524 -0.3048) (xy 0.1524 0.3048) (xy -0.1524 0.3048) (xy -0.1524 -0.1778)
				(xy -0.2794 -0.1778) (xy -0.2794 0.6477)
			)
			(stroke
				(width 0)
				(type default)
			)
			(fill no)
			(layer "B.CrtYd")
		)
		(fp_rect
			(start 0.2794 0.6477)
			(end -0.2794 -0.6477)
			(stroke
				(width 0)
				(type default)
			)
			(fill no)
			(layer "B.Fab")
		)
		(pad "1" smd custom
			(at 0 -0.2794 90)
			(size 0.0762 0.0762)
			(layers "B.Cu" "B.Mask" "B.Paste")
			(net "SYS_PLL_VDD")
			(options
				(clearance outline)
				(anchor circle)
			)
			(primitives
				(gr_poly
					(pts
						(arc
							(start 0.1524 0.127)
							(mid 0.137521 0.162921)
							(end 0.1016 0.1778)
						)
						(arc
							(start -0.1016 0.1778)
							(mid -0.137521 0.162921)
							(end -0.1524 0.127)
						)
						(arc
							(start -0.1524 -0.127)
							(mid -0.137521 -0.162921)
							(end -0.1016 -0.1778)
						)
						(arc
							(start 0.1016 -0.1778)
							(mid 0.137521 -0.162921)
							(end 0.1524 -0.127)
						)
					)
					(width 0)
					(fill yes)
				)
			)
		)
		(pad "2" smd custom
			(at 0 0.2794 90)
			(size 0.0762 0.0762)
			(layers "B.Cu" "B.Mask" "B.Paste")
			(net "GND")
			(options
				(clearance outline)
				(anchor circle)
			)
			(primitives
				(gr_poly
					(pts
						(arc
							(start 0.1524 0.127)
							(mid 0.137521 0.162921)
							(end 0.1016 0.1778)
						)
						(arc
							(start -0.1016 0.1778)
							(mid -0.137521 0.162921)
							(end -0.1524 0.127)
						)
						(arc
							(start -0.1524 -0.127)
							(mid -0.137521 -0.162921)
							(end -0.1016 -0.1778)
						)
						(arc
							(start 0.1016 -0.1778)
							(mid 0.137521 -0.162921)
							(end 0.1524 -0.127)
						)
					)
					(width 0)
					(fill yes)
				)
			)
		)
	)
	(footprint ""
		(layer "B.Cu")
		(at 192.942718 -81.153 180)
		(property "Reference" "C298"
			(at 0 0 0)
			(layer "B.SilkS")
			(hide yes)
			(effects
				(font
					(size 1.27 1.27)
				)
				(justify mirror)
			)
		)
		(property "Value" "SCD22U10V1KX-GP"
			(at 2.8321 -1.7399 180)
			(unlocked yes)
			(layer "B.Fab")
			(hide yes)
			(effects
				(font
					(size 1.016 1.016)
					(thickness 0.1524)
				)
				(justify mirror)
			)
		)
		(property "Device Type" "C0201H13"
			(at 2.8321 -3.2639 180)
			(unlocked yes)
			(layer "B.Fab")
			(hide yes)
			(effects
				(font
					(size 1.016 1.016)
					(thickness 0.1524)
				)
				(justify mirror)
			)
		)
		(duplicate_pad_numbers_are_jumpers no)
		(fp_rect
			(start 0.2794 0.6477)
			(end -0.2794 -0.6477)
			(stroke
				(width 0)
				(type default)
			)
			(fill no)
			(layer "B.CrtYd")
		)
		(fp_rect
			(start 0.2794 0.6477)
			(end -0.2794 -0.6477)
			(stroke
				(width 0)
				(type default)
			)
			(fill no)
			(layer "B.Fab")
		)
		(pad "1" smd custom
			(at 0 -0.2794)
			(size 0.0762 0.0762)
			(layers "B.Cu" "B.Mask" "B.Paste")
			(net "PCIE_IOM_TO_COMP_12_DN_C")
			(options
				(clearance outline)
				(anchor circle)
			)
			(primitives
				(gr_poly
					(pts
						(arc
							(start 0.1524 0.127)
							(mid 0.137521 0.162921)
							(end 0.1016 0.1778)
						)
						(arc
							(start -0.1016 0.1778)
							(mid -0.137521 0.162921)
							(end -0.1524 0.127)
						)
						(arc
							(start -0.1524 -0.127)
							(mid -0.137521 -0.162921)
							(end -0.1016 -0.1778)
						)
						(arc
							(start 0.1016 -0.1778)
							(mid 0.137521 -0.162921)
							(end 0.1524 -0.127)
						)
					)
					(width 0)
					(fill yes)
				)
			)
		)
		(pad "2" smd custom
			(at 0 0.2794)
			(size 0.0762 0.0762)
			(layers "B.Cu" "B.Mask" "B.Paste")
			(net "PCIE_IOM_TO_COMP_12_DN")
			(options
				(clearance outline)
				(anchor circle)
			)
			(primitives
				(gr_poly
					(pts
						(arc
							(start 0.1524 0.127)
							(mid 0.137521 0.162921)
							(end 0.1016 0.1778)
						)
						(arc
							(start -0.1016 0.1778)
							(mid -0.137521 0.162921)
							(end -0.1524 0.127)
						)
						(arc
							(start -0.1524 -0.127)
							(mid -0.137521 -0.162921)
							(end -0.1016 -0.1778)
						)
						(arc
							(start 0.1016 -0.1778)
							(mid 0.137521 -0.162921)
							(end 0.1524 -0.127)
						)
					)
					(width 0)
					(fill yes)
				)
			)
		)
	)
	(footprint ""
		(layer "B.Cu")
		(at 10.20445 -133.85673 90)
		(property "Reference" "R242"
			(at 0 0 90)
			(layer "B.SilkS")
			(hide yes)
			(effects
				(font
					(size 1.27 1.27)
				)
				(justify mirror)
			)
		)
		(property "Value" "120R2F-GP"
			(at -0.064008 -3.993896 90)
			(unlocked yes)
			(layer "B.Fab")
			(hide yes)
			(effects
				(font
					(size 1.016 1.016)
					(thickness 0.1524)
				)
				(justify mirror)
			)
		)
		(property "Device Type" "R402H16"
			(at -0.064008 -5.517896 90)
			(unlocked yes)
			(layer "B.Fab")
			(hide yes)
			(effects
				(font
					(size 1.016 1.016)
					(thickness 0.1524)
				)
				(justify mirror)
			)
		)
		(duplicate_pad_numbers_are_jumpers no)
		(fp_line
			(start 0.508 -0.9398)
			(end 0.508 0.9398)
			(stroke
				(width 0.1524)
				(type default)
			)
			(layer "B.SilkS")
		)
		(fp_line
			(start -0.508 -0.9398)
			(end 0.508 -0.9398)
			(stroke
				(width 0.1524)
				(type default)
			)
			(layer "B.SilkS")
		)
		(fp_rect
			(start 0.508 0.9398)
			(end -0.508 -0.9398)
			(stroke
				(width 0)
				(type default)
			)
			(fill no)
			(layer "B.CrtYd")
		)
		(fp_rect
			(start 0.508 0.9398)
			(end -0.508 -0.9398)
			(stroke
				(width 0)
				(type default)
			)
			(fill no)
			(layer "B.Fab")
		)
		(pad "1" smd custom
			(at 0 -0.4445 270)
			(size 0.1397 0.1397)
			(layers "B.Cu" "B.Mask" "B.Paste")
			(net "GND")
			(options
				(clearance outline)
				(anchor circle)
			)
			(primitives
				(gr_poly
					(pts
						(arc
							(start -0.1778 0.2794)
							(mid -0.249642 0.249642)
							(end -0.2794 0.1778)
						)
						(arc
							(start -0.2794 -0.1778)
							(mid -0.249642 -0.249642)
							(end -0.1778 -0.2794)
						)
						(arc
							(start 0.1778 -0.2794)
							(mid 0.249642 -0.249642)
							(end 0.2794 -0.1778)
						)
						(arc
							(start 0.2794 0.1778)
							(mid 0.249642 0.249642)
							(end 0.1778 0.2794)
						)
					)
					(width 0)
					(fill yes)
				)
			)
		)
		(pad "2" smd custom
			(at 0 0.4445 270)
			(size 0.1397 0.1397)
			(layers "B.Cu" "B.Mask" "B.Paste")
			(net "MEMA_4")
			(options
				(clearance outline)
				(anchor circle)
			)
			(primitives
				(gr_poly
					(pts
						(arc
							(start -0.1778 0.2794)
							(mid -0.249642 0.249642)
							(end -0.2794 0.1778)
						)
						(arc
							(start -0.2794 -0.1778)
							(mid -0.249642 -0.249642)
							(end -0.1778 -0.2794)
						)
						(arc
							(start 0.1778 -0.2794)
							(mid 0.249642 -0.249642)
							(end 0.2794 -0.1778)
						)
						(arc
							(start 0.2794 0.1778)
							(mid 0.249642 0.249642)
							(end 0.1778 0.2794)
						)
					)
					(width 0)
					(fill yes)
				)
			)
		)
	)
	(footprint ""
		(layer "B.Cu")
		(at 68.820538 -145.974816 180)
		(property "Reference" "R193"
			(at 0 0 0)
			(layer "B.SilkS")
			(hide yes)
			(effects
				(font
					(size 1.27 1.27)
				)
				(justify mirror)
			)
		)
		(property "Value" "20KR2F-L-GP"
			(at -0.064008 -3.993896 180)
			(unlocked yes)
			(layer "B.Fab")
			(hide yes)
			(effects
				(font
					(size 1.016 1.016)
					(thickness 0.1524)
				)
				(justify mirror)
			)
		)
		(property "Device Type" "R402H16"
			(at -0.064008 -5.517896 180)
			(unlocked yes)
			(layer "B.Fab")
			(hide yes)
			(effects
				(font
					(size 1.016 1.016)
					(thickness 0.1524)
				)
				(justify mirror)
			)
		)
		(duplicate_pad_numbers_are_jumpers no)
		(fp_line
			(start 0.508 -0.9398)
			(end 0.508 0.9398)
			(stroke
				(width 0.1524)
				(type default)
			)
			(layer "B.SilkS")
		)
		(fp_line
			(start -0.508 -0.9398)
			(end 0.508 -0.9398)
			(stroke
				(width 0.1524)
				(type default)
			)
			(layer "B.SilkS")
		)
		(fp_rect
			(start 0.508 0.9398)
			(end -0.508 -0.9398)
			(stroke
				(width 0)
				(type default)
			)
			(fill no)
			(layer "B.CrtYd")
		)
		(fp_rect
			(start 0.508 0.9398)
			(end -0.508 -0.9398)
			(stroke
				(width 0)
				(type default)
			)
			(fill no)
			(layer "B.Fab")
		)
		(pad "1" smd custom
			(at 0 -0.4445)
			(size 0.1397 0.1397)
			(layers "B.Cu" "B.Mask" "B.Paste")
			(net "P3V3_STBY")
			(options
				(clearance outline)
				(anchor circle)
			)
			(primitives
				(gr_poly
					(pts
						(arc
							(start -0.1778 0.2794)
							(mid -0.249642 0.249642)
							(end -0.2794 0.1778)
						)
						(arc
							(start -0.2794 -0.1778)
							(mid -0.249642 -0.249642)
							(end -0.1778 -0.2794)
						)
						(arc
							(start 0.1778 -0.2794)
							(mid 0.249642 -0.249642)
							(end 0.2794 -0.1778)
						)
						(arc
							(start 0.2794 0.1778)
							(mid 0.249642 0.249642)
							(end 0.1778 0.2794)
						)
					)
					(width 0)
					(fill yes)
				)
			)
		)
		(pad "2" smd custom
			(at 0 0.4445)
			(size 0.1397 0.1397)
			(layers "B.Cu" "B.Mask" "B.Paste")
			(net "I2C_DEBUG_SCL_L")
			(options
				(clearance outline)
				(anchor circle)
			)
			(primitives
				(gr_poly
					(pts
						(arc
							(start -0.1778 0.2794)
							(mid -0.249642 0.249642)
							(end -0.2794 0.1778)
						)
						(arc
							(start -0.2794 -0.1778)
							(mid -0.249642 -0.249642)
							(end -0.1778 -0.2794)
						)
						(arc
							(start 0.1778 -0.2794)
							(mid 0.249642 -0.249642)
							(end 0.2794 -0.1778)
						)
						(arc
							(start 0.2794 0.1778)
							(mid 0.249642 0.249642)
							(end 0.1778 0.2794)
						)
					)
					(width 0)
					(fill yes)
				)
			)
		)
	)
)
